# BASEBOARD_FAB2 (Tioga Pass) — schematic netlist excerpt (pin names and nets, part order shuffled) for the footprints in the layout excerpt that follows; sources: Cadence DE-HDL packaged netlist, KiCad conversion of Wiwynn_Tioga_Pass_MB.brd

R25W44  120R2F-GP  1%  pkg RCL_GP  page 151 : \1\ = BMC_M_A6 ; \2\ = P1V2_AUX_BMC
R30W4  RES  0.0 5% CHIP  pkg 0402  page 253 : A = USB3_P01_C_TXP ; B = USB3_P01_FB_TXP
C1L5  CAP_A  1.0UF 6.3V 10% X6S  pkg 0402V  page 111 : A = P1V05_PCH_STBY ; B = GND

(kicad_pcb
	(version 20260206)
	(generator "pcbnew")
	(generator_version "10.0")
	(general
		(thickness 1.6)
		(legacy_teardrops no)
	)
	(paper "A4")
	(title_block
		(title "Wiwynn_Tioga_Pass_MB.brd")
		(comment 1 "Tioga Pass / footprints 4477-4479 of 4770")
	)
	(layers
		(0 "F.Cu" signal "TOP")
		(4 "In1.Cu" signal "L2GND")
		(6 "In2.Cu" signal "L3")
		(8 "In3.Cu" signal "L4GND")
		(10 "In4.Cu" signal "L5")
		(12 "In5.Cu" signal "L6GND")
		(14 "In6.Cu" signal "L7VCC")
		(16 "In7.Cu" signal "L8VCC")
		(18 "In8.Cu" signal "L9GND")
		(20 "In9.Cu" signal "L10")
		(22 "In10.Cu" signal "L11GND")
		(24 "In11.Cu" signal "L12")
		(26 "In12.Cu" signal "L13GND")
		(2 "B.Cu" signal "BOTTOM")
		(9 "F.Adhes" user "F.Adhesive")
		(11 "B.Adhes" user "B.Adhesive")
		(13 "F.Paste" user "Package Geometry/Pastemask Top")
		(15 "B.Paste" user "Package Geometry/Pastemask Bottom")
		(5 "F.SilkS" user "Ref Des/Silkscreen Top")
		(7 "B.SilkS" user "Ref Des/Silkscreen Bottom")
		(1 "F.Mask" user "Board Geometry/Soldermask Top")
		(3 "B.Mask" user "Board Geometry/Soldermask Bottom")
		(17 "Dwgs.User" user "User.Drawings")
		(19 "Cmts.User" user "User.Comments")
		(21 "Eco1.User" user "User.Eco1")
		(23 "Eco2.User" user "User.Eco2")
		(25 "Edge.Cuts" user "Board Geometry/Outline")
		(27 "Margin" user)
		(31 "F.CrtYd" user "Package Geometry/Place Bound Top")
		(29 "B.CrtYd" user "Package Geometry/Place Bound Bottom")
		(35 "F.Fab" user "Ref Des/Assembly Top")
		(33 "B.Fab" user "Ref Des/Assembly Bottom")
	)
	(footprint ""
		(layer "B.Cu")
		(at 444.548006 -43.54195 180)
		(property "Reference" "R25W44"
			(at 0 0 0)
			(layer "B.SilkS")
			(hide yes)
			(effects
				(font
					(size 1.27 1.27)
				)
				(justify mirror)
			)
		)
		(property "Value" "*"
			(at -0.064008 -4.108196 180)
			(unlocked yes)
			(layer "B.Fab")
			(hide yes)
			(effects
				(font
					(size 1.27 1.016)
					(thickness 0.1524)
				)
				(justify mirror)
			)
		)
		(property "Device Type" "120R2F-GP_RCL_GP-120R2F-GP,64.A"
			(at -0.064008 -5.632196 180)
			(unlocked yes)
			(layer "B.Fab")
			(hide yes)
			(effects
				(font
					(size 1.27 1.016)
					(thickness 0.1524)
				)
				(justify mirror)
			)
		)
		(duplicate_pad_numbers_are_jumpers no)
		(fp_line
			(start 0.508 -0.9398)
			(end 0.508 0.9398)
			(stroke
				(width 0.1524)
				(type default)
			)
			(layer "B.SilkS")
		)
		(fp_line
			(start -0.508 -0.9398)
			(end 0.508 -0.9398)
			(stroke
				(width 0.1524)
				(type default)
			)
			(layer "B.SilkS")
		)
		(fp_rect
			(start 0.508 0.9398)
			(end -0.508 -0.9398)
			(stroke
				(width 0)
				(type default)
			)
			(fill no)
			(layer "B.CrtYd")
		)
		(fp_rect
			(start 0.508 0.9398)
			(end -0.508 -0.9398)
			(stroke
				(width 0)
				(type default)
			)
			(fill no)
			(layer "B.Fab")
		)
		(pad "1" smd custom
			(at 0 -0.4445)
			(size 0.1397 0.1397)
			(layers "B.Cu" "B.Mask" "B.Paste")
			(net "BMC_M_A6")
			(options
				(clearance outline)
				(anchor circle)
			)
			(primitives
				(gr_poly
					(pts
						(arc
							(start -0.1778 0.2794)
							(mid -0.249642 0.249642)
							(end -0.2794 0.1778)
						)
						(arc
							(start -0.2794 -0.1778)
							(mid -0.249642 -0.249642)
							(end -0.1778 -0.2794)
						)
						(arc
							(start 0.1778 -0.2794)
							(mid 0.249642 -0.249642)
							(end 0.2794 -0.1778)
						)
						(arc
							(start 0.2794 0.1778)
							(mid 0.249642 0.249642)
							(end 0.1778 0.2794)
						)
					)
					(width 0)
					(fill yes)
				)
			)
		)
		(pad "2" smd custom
			(at 0 0.4445)
			(size 0.1397 0.1397)
			(layers "B.Cu" "B.Mask" "B.Paste")
			(net "P1V2_AUX_BMC")
			(options
				(clearance outline)
				(anchor circle)
			)
			(primitives
				(gr_poly
					(pts
						(arc
							(start -0.1778 0.2794)
							(mid -0.249642 0.249642)
							(end -0.2794 0.1778)
						)
						(arc
							(start -0.2794 -0.1778)
							(mid -0.249642 -0.249642)
							(end -0.1778 -0.2794)
						)
						(arc
							(start 0.1778 -0.2794)
							(mid 0.249642 -0.249642)
							(end 0.2794 -0.1778)
						)
						(arc
							(start 0.2794 0.1778)
							(mid 0.249642 0.249642)
							(end 0.1778 0.2794)
						)
					)
					(width 0)
					(fill yes)
				)
			)
		)
	)
	(footprint ""
		(layer "B.Cu")
		(at 461.899 -146.304 90)
		(property "Reference" "C1L5"
			(at 0 0 90)
			(layer "B.SilkS")
			(hide yes)
			(effects
				(font
					(size 1.27 1.27)
				)
				(justify mirror)
			)
		)
		(property "Value" ""
			(at 0 0 90)
			(layer "B.Fab")
			(effects
				(font
					(size 1.27 1.27)
				)
				(justify mirror)
			)
		)
		(duplicate_pad_numbers_are_jumpers no)
		(fp_poly
			(pts
				(xy -0.3048 -0.1016) (xy -0.3048 0.9906) (xy 0.3048 0.9906) (xy 0.3048 -0.1016)
			)
			(stroke
				(width 0)
				(type default)
			)
			(fill no)
			(layer "B.CrtYd")
		)
		(fp_line
			(start 0.3048 -0.1016)
			(end 0.3048 0.9906)
			(stroke
				(width 0.1)
				(type default)
			)
			(layer "B.Fab")
		)
		(fp_line
			(start -0.3048 -0.1016)
			(end 0.3048 -0.1016)
			(stroke
				(width 0.1)
				(type default)
			)
			(layer "B.Fab")
		)
		(fp_line
			(start 0.3048 0.9906)
			(end -0.3048 0.9906)
			(stroke
				(width 0.1)
				(type default)
			)
			(layer "B.Fab")
		)
		(fp_line
			(start -0.3048 0.9906)
			(end -0.3048 -0.1016)
			(stroke
				(width 0.1)
				(type default)
			)
			(layer "B.Fab")
		)
		(pad "1" smd rect
			(at 0 0 270)
			(size 0.508 0.508)
			(layers "B.Cu" "B.Mask" "B.Paste")
			(net "P1V05_PCH_STBY")
		)
		(pad "2" smd rect
			(at 0 0.889 270)
			(size 0.508 0.508)
			(layers "B.Cu" "B.Mask" "B.Paste")
			(net "GND")
		)
		(zone
			(layer "B.Cu")
			(hatch none 0.5)
			(connect_pads
				(clearance 0)
			)
			(min_thickness 0.25)
			(keepout
				(tracks allowed)
				(vias not_allowed)
				(pads allowed)
				(copperpour not_allowed)
				(footprints allowed)
			)
			(placement
				(enabled no)
				(sheetname "")
			)
			(fill
				(thermal_gap 0.5)
				(thermal_bridge_width 0.5)
				(island_removal_mode 0)
			)
			(polygon
				(pts
					(xy 462.153 -146.558) (xy 462.153 -146.05) (xy 462.534 -146.05) (xy 462.534 -146.558)
				)
			)
		)
		(zone
			(layer "B.Cu")
			(hatch none 0.5)
			(connect_pads
				(clearance 0)
			)
			(min_thickness 0.25)
			(keepout
				(tracks not_allowed)
				(vias allowed)
				(pads allowed)
				(copperpour not_allowed)
				(footprints allowed)
			)
			(placement
				(enabled no)
				(sheetname "")
			)
			(fill
				(thermal_gap 0.5)
				(thermal_bridge_width 0.5)
				(island_removal_mode 0)
			)
			(polygon
				(pts
					(xy 462.534 -146.558) (xy 462.534 -146.05) (xy 462.153 -146.05) (xy 462.153 -146.558)
				)
			)
		)
	)
	(footprint ""
		(layer "B.Cu")
		(at 488.22864 -60.024772 90)
		(property "Reference" "R30W4"
			(at 0.8382 -0.67818 90)
			(unlocked yes)
			(layer "B.SilkS")
			(effects
				(font
					(size 0.4064 0.254)
					(thickness 0.1524)
				)
				(justify left mirror)
			)
		)
		(property "Value" ""
			(at 0 0 90)
			(layer "B.Fab")
			(effects
				(font
					(size 1.27 1.27)
				)
				(justify mirror)
			)
		)
		(duplicate_pad_numbers_are_jumpers no)
		(fp_poly
			(pts
				(xy 0.2794 -0.1016) (xy -0.2794 -0.1016) (xy -0.2794 0.9906) (xy 0.2794 0.9906)
			)
			(stroke
				(width 0)
				(type default)
			)
			(fill no)
			(layer "B.CrtYd")
		)
		(fp_line
			(start 0.2794 -0.1016)
			(end 0.2794 0.9906)
			(stroke
				(width 0.1)
				(type default)
			)
			(layer "B.Fab")
		)
		(fp_line
			(start -0.2794 -0.1016)
			(end 0.2794 -0.1016)
			(stroke
				(width 0.1)
				(type default)
			)
			(layer "B.Fab")
		)
		(fp_line
			(start 0.2794 0.9906)
			(end -0.2794 0.9906)
			(stroke
				(width 0.1)
				(type default)
			)
			(layer "B.Fab")
		)
		(fp_line
			(start -0.2794 0.9906)
			(end -0.2794 -0.1016)
			(stroke
				(width 0.1)
				(type default)
			)
			(layer "B.Fab")
		)
		(pad "1" smd rect
			(at 0 0 270)
			(size 0.508 0.508)
			(layers "B.Cu" "B.Mask" "B.Paste")
			(net "USB3_P01_C_TXP")
		)
		(pad "2" smd rect
			(at 0 0.889 270)
			(size 0.508 0.508)
			(layers "B.Cu" "B.Mask" "B.Paste")
			(net "USB3_P01_FB_TXP")
		)
		(zone
			(layer "B.Cu")
			(hatch none 0.5)
			(connect_pads
				(clearance 0)
			)
			(min_thickness 0.25)
			(keepout
				(tracks allowed)
				(vias not_allowed)
				(pads allowed)
				(copperpour not_allowed)
				(footprints allowed)
			)
			(placement
				(enabled no)
				(sheetname "")
			)
			(fill
				(thermal_gap 0.5)
				(thermal_bridge_width 0.5)
				(island_removal_mode 0)
			)
			(polygon
				(pts
					(xy 488.48264 -60.278772) (xy 488.48264 -59.770772) (xy 488.86364 -59.770772) (xy 488.86364 -60.278772)
				)
			)
		)
		(zone
			(layer "B.Cu")
			(hatch none 0.5)
			(connect_pads
				(clearance 0)
			)
			(min_thickness 0.25)
			(keepout
				(tracks not_allowed)
				(vias allowed)
				(pads allowed)
				(copperpour not_allowed)
				(footprints allowed)
			)
			(placement
				(enabled no)
				(sheetname "")
			)
			(fill
				(thermal_gap 0.5)
				(thermal_bridge_width 0.5)
				(island_removal_mode 0)
			)
			(polygon
				(pts
					(xy 488.86364 -60.278772) (xy 488.86364 -59.770772) (xy 488.48264 -59.770772) (xy 488.48264 -60.278772)
				)
			)
		)
	)
)
